(kicad_pcb
	(version 20260206)
	(generator "pcbnew")
	(generator_version "10.0")
	(general
		(thickness 1.6)
		(legacy_teardrops no)
	)
	(paper "A4")
	(title_block
		(title "04192023_DAF0TMB3IC0_F0TG_MB_C_brd_V02_OCP.brd")
		(comment 1 "Grand Teton / footprints 16-23 of 8354")
	)
	(layers
		(0 "F.Cu" signal "TOP")
		(4 "In1.Cu" signal "GND")
		(6 "In2.Cu" signal "IN1")
		(8 "In3.Cu" signal "GND1")
		(10 "In4.Cu" signal "IN2")
		(12 "In5.Cu" signal "GND2")
		(14 "In6.Cu" signal "IN3")
		(16 "In7.Cu" signal "GND3")
		(18 "In8.Cu" signal "VCC")
		(20 "In9.Cu" signal "VCC1")
		(22 "In10.Cu" signal "GND4")
		(24 "In11.Cu" signal "IN4")
		(26 "In12.Cu" signal "GND5")
		(28 "In13.Cu" signal "IN5")
		(30 "In14.Cu" signal "GND6")
		(32 "In15.Cu" signal "IN6")
		(34 "In16.Cu" signal "GND7")
		(2 "B.Cu" signal "BOTTOM")
		(9 "F.Adhes" user "F.Adhesive")
		(11 "B.Adhes" user "B.Adhesive")
		(13 "F.Paste" user "Package Geometry/Pastemask Top")
		(15 "B.Paste" user "Package Geometry/Pastemask Bottom")
		(5 "F.SilkS" user "Ref Des/Silkscreen Top")
		(7 "B.SilkS" user "Ref Des/Silkscreen Bottom")
		(1 "F.Mask" user "Board Geometry/Soldermask Top")
		(3 "B.Mask" user "Board Geometry/Soldermask Bottom")
		(17 "Dwgs.User" user "User.Drawings")
		(19 "Cmts.User" user "User.Comments")
		(21 "Eco1.User" user "User.Eco1")
		(23 "Eco2.User" user "User.Eco2")
		(25 "Edge.Cuts" user "Board Geometry/Outline")
		(27 "Margin" user)
		(31 "F.CrtYd" user "Package Geometry/Place Bound Top")
		(29 "B.CrtYd" user "Package Geometry/Place Bound Bottom")
		(35 "F.Fab" user "Ref Des/Assembly Top")
		(33 "B.Fab" user "Ref Des/Assembly Bottom")
	)
	(footprint ""
		(layer "F.Cu")
		(at 9.277096 -100.017834 90)
		(property "Reference" "C2029"
			(at 0 0 90)
			(layer "F.SilkS")
			(hide yes)
			(effects
				(font
					(size 1.27 1.27)
				)
			)
		)
		(property "Value" ""
			(at 0 0 90)
			(layer "F.Fab")
			(effects
				(font
					(size 1.27 1.27)
				)
			)
		)
		(duplicate_pad_numbers_are_jumpers no)
		(fp_line
			(start 0.7874 -0.4064)
			(end 0.7874 0.4064)
			(stroke
				(width 0.1524)
				(type default)
			)
			(layer "F.SilkS")
		)
		(fp_line
			(start -0.7874 -0.4064)
			(end 0.7874 -0.4064)
			(stroke
				(width 0.1524)
				(type default)
			)
			(layer "F.SilkS")
		)
		(fp_line
			(start 0.7874 0.4064)
			(end -0.7874 0.4064)
			(stroke
				(width 0.1524)
				(type default)
			)
			(layer "F.SilkS")
		)
		(fp_line
			(start -0.7874 0.4064)
			(end -0.7874 -0.4064)
			(stroke
				(width 0.1524)
				(type default)
			)
			(layer "F.SilkS")
		)
		(fp_line
			(start -0.12065 -0.305054)
			(end -0.12065 -0.2794)
			(stroke
				(width 0.1)
				(type default)
			)
			(layer "F.Fab")
		)
		(fp_line
			(start -0.67945 -0.305054)
			(end -0.12065 -0.305054)
			(stroke
				(width 0.1)
				(type default)
			)
			(layer "F.Fab")
		)
		(fp_line
			(start 0.67945 -0.3048)
			(end 0.67945 0.3048)
			(stroke
				(width 0.1)
				(type default)
			)
			(layer "F.Fab")
		)
		(fp_line
			(start 0.12065 -0.3048)
			(end 0.67945 -0.3048)
			(stroke
				(width 0.1)
				(type default)
			)
			(layer "F.Fab")
		)
		(fp_line
			(start 0.12065 -0.2794)
			(end 0.12065 -0.3048)
			(stroke
				(width 0.1)
				(type default)
			)
			(layer "F.Fab")
		)
		(fp_line
			(start -0.12065 -0.2794)
			(end 0.12065 -0.2794)
			(stroke
				(width 0.1)
				(type default)
			)
			(layer "F.Fab")
		)
		(fp_line
			(start 0.120396 0.2794)
			(end -0.12065 0.2794)
			(stroke
				(width 0.1)
				(type default)
			)
			(layer "F.Fab")
		)
		(fp_line
			(start -0.12065 0.2794)
			(end -0.12065 0.3048)
			(stroke
				(width 0.1)
				(type default)
			)
			(layer "F.Fab")
		)
		(fp_line
			(start 0.67945 0.3048)
			(end 0.120396 0.3048)
			(stroke
				(width 0.1)
				(type default)
			)
			(layer "F.Fab")
		)
		(fp_line
			(start 0.120396 0.3048)
			(end 0.120396 0.2794)
			(stroke
				(width 0.1)
				(type default)
			)
			(layer "F.Fab")
		)
		(fp_line
			(start -0.12065 0.3048)
			(end -0.67945 0.3048)
			(stroke
				(width 0.1)
				(type default)
			)
			(layer "F.Fab")
		)
		(fp_line
			(start -0.67945 0.3048)
			(end -0.67945 -0.305054)
			(stroke
				(width 0.1)
				(type default)
			)
			(layer "F.Fab")
		)
		(pad "1" smd circle
			(at -0.40005 0 90)
			(size 0 0)
			(layers "F.Cu" "F.Mask" "F.Paste")
			(net "USB_HUB_XTAL_IN")
		)
		(pad "2" smd circle
			(at 0.40005 0 90)
			(size 0 0)
			(layers "F.Cu" "F.Mask" "F.Paste")
			(net "GND")
		)
	)
	(footprint ""
		(layer "F.Cu")
		(at 294.560752 -422.173908 90)
		(property "Reference" "R668"
			(at 0 0 90)
			(layer "F.SilkS")
			(hide yes)
			(effects
				(font
					(size 1.27 1.27)
				)
			)
		)
		(property "Value" ""
			(at 0 0 90)
			(layer "F.Fab")
			(effects
				(font
					(size 1.27 1.27)
				)
			)
		)
		(duplicate_pad_numbers_are_jumpers no)
		(fp_line
			(start 0.32512 -0.175006)
			(end 0.32512 0.175006)
			(stroke
				(width 0.1)
				(type default)
			)
			(layer "F.Fab")
		)
		(fp_line
			(start -0.32512 -0.175006)
			(end 0.32512 -0.175006)
			(stroke
				(width 0.1)
				(type default)
			)
			(layer "F.Fab")
		)
		(fp_line
			(start 0.32512 0.175006)
			(end -0.32512 0.175006)
			(stroke
				(width 0.1)
				(type default)
			)
			(layer "F.Fab")
		)
		(fp_line
			(start -0.32512 0.175006)
			(end -0.32512 -0.175006)
			(stroke
				(width 0.1)
				(type default)
			)
			(layer "F.Fab")
		)
		(pad "1" smd rect
			(at -0.2667 0 90)
			(size 0.3048 0.381)
			(layers "F.Cu" "F.Mask" "F.Paste")
			(net "SMB_RT_CPU0_P0_ROM_R_SCL")
		)
		(pad "2" smd rect
			(at 0.2667 0 270)
			(size 0.3048 0.381)
			(layers "F.Cu" "F.Mask" "F.Paste")
			(net "SMB_RT_CPU0_P0_ROM_SCL")
		)
	)
	(footprint ""
		(layer "F.Cu")
		(at 44.691554 -370.57203 -90)
		(property "Reference" "C831"
			(at 0 0 270)
			(layer "F.SilkS")
			(hide yes)
			(effects
				(font
					(size 1.27 1.27)
				)
			)
		)
		(property "Value" ""
			(at 0 0 270)
			(layer "F.Fab")
			(effects
				(font
					(size 1.27 1.27)
				)
			)
		)
		(duplicate_pad_numbers_are_jumpers no)
		(fp_line
			(start -0.299974 0.150114)
			(end -0.299974 -0.150114)
			(stroke
				(width 0.1)
				(type default)
			)
			(layer "F.Fab")
		)
		(fp_line
			(start 0.299974 0.150114)
			(end -0.299974 0.150114)
			(stroke
				(width 0.1)
				(type default)
			)
			(layer "F.Fab")
		)
		(fp_line
			(start -0.299974 -0.150114)
			(end 0.299974 -0.150114)
			(stroke
				(width 0.1)
				(type default)
			)
			(layer "F.Fab")
		)
		(fp_line
			(start 0.299974 -0.150114)
			(end 0.299974 0.150114)
			(stroke
				(width 0.1)
				(type default)
			)
			(layer "F.Fab")
		)
		(pad "1" smd rect
			(at -0.2667 0 270)
			(size 0.3048 0.381)
			(layers "F.Cu" "F.Mask" "F.Paste")
			(net "P5E_CPU1_P0_TX_C_DP<3>")
		)
		(pad "2" smd rect
			(at 0.2667 0 270)
			(size 0.3048 0.381)
			(layers "F.Cu" "F.Mask" "F.Paste")
			(net "P5E_CPU1_P0_TX_DP<3>")
		)
	)
	(footprint ""
		(layer "F.Cu")
		(at 76.211176 -355.008434 90)
		(property "Reference" "PC393"
			(at -5.277104 -1.789176 0)
			(unlocked yes)
			(layer "F.SilkS")
			(effects
				(font
					(size 0.7874 0.5842)
					(thickness 0.1524)
				)
				(justify left)
			)
		)
		(property "Value" ""
			(at 0 0 90)
			(layer "F.Fab")
			(effects
				(font
					(size 1.27 1.27)
				)
			)
		)
		(duplicate_pad_numbers_are_jumpers no)
		(fp_line
			(start 3.400044 -3.400044)
			(end -2.146046 -3.400044)
			(stroke
				(width 0.1524)
				(type default)
			)
			(layer "F.SilkS")
		)
		(fp_line
			(start -2.146046 -3.400044)
			(end -3.400044 -2.146046)
			(stroke
				(width 0.1524)
				(type default)
			)
			(layer "F.SilkS")
		)
		(fp_line
			(start -3.400044 -2.146046)
			(end -3.400044 -0.9398)
			(stroke
				(width 0.1524)
				(type default)
			)
			(layer "F.SilkS")
		)
		(fp_line
			(start 3.400044 -0.9398)
			(end 3.400044 -3.400044)
			(stroke
				(width 0.1524)
				(type default)
			)
			(layer "F.SilkS")
		)
		(fp_line
			(start 3.400044 0.9398)
			(end 3.400044 3.400044)
			(stroke
				(width 0.1524)
				(type default)
			)
			(layer "F.SilkS")
		)
		(fp_line
			(start -3.400044 2.146046)
			(end -3.400044 0.9398)
			(stroke
				(width 0.1524)
				(type default)
			)
			(layer "F.SilkS")
		)
		(fp_line
			(start 3.400044 3.400044)
			(end -2.146046 3.400044)
			(stroke
				(width 0.1524)
				(type default)
			)
			(layer "F.SilkS")
		)
		(fp_line
			(start -2.146046 3.400044)
			(end -3.400044 2.146046)
			(stroke
				(width 0.1524)
				(type default)
			)
			(layer "F.SilkS")
		)
		(fp_line
			(start 3.400044 -3.400044)
			(end -3.400044 -3.400044)
			(stroke
				(width 0.1)
				(type default)
			)
			(layer "F.Fab")
		)
		(fp_line
			(start -3.400044 -3.400044)
			(end -3.400044 3.400044)
			(stroke
				(width 0.1)
				(type default)
			)
			(layer "F.Fab")
		)
		(fp_line
			(start 3.400044 3.400044)
			(end 3.400044 -3.400044)
			(stroke
				(width 0.1)
				(type default)
			)
			(layer "F.Fab")
		)
		(fp_line
			(start -3.400044 3.400044)
			(end 3.400044 3.400044)
			(stroke
				(width 0.1)
				(type default)
			)
			(layer "F.Fab")
		)
		(pad "1" smd rect
			(at -2.70002 0)
			(size 1.6002 3.5052)
			(layers "F.Cu" "F.Mask" "F.Paste")
			(net "SW_P12V_AUX_PVDDCR_CPU1_P1_FLT")
		)
		(pad "2" smd rect
			(at 2.70002 0)
			(size 1.6002 3.5052)
			(layers "F.Cu" "F.Mask" "F.Paste")
			(net "GND")
		)
	)
	(footprint ""
		(layer "F.Cu")
		(at 177.673 -100.294948 90)
		(property "Reference" "R236"
			(at 0 0 90)
			(layer "F.SilkS")
			(hide yes)
			(effects
				(font
					(size 1.27 1.27)
				)
			)
		)
		(property "Value" ""
			(at 0 0 90)
			(layer "F.Fab")
			(effects
				(font
					(size 1.27 1.27)
				)
			)
		)
		(duplicate_pad_numbers_are_jumpers no)
		(fp_line
			(start 0.7874 -0.4064)
			(end 0.7874 0.4064)
			(stroke
				(width 0.1524)
				(type default)
			)
			(layer "F.SilkS")
		)
		(fp_line
			(start -0.7874 -0.4064)
			(end 0.7874 -0.4064)
			(stroke
				(width 0.1524)
				(type default)
			)
			(layer "F.SilkS")
		)
		(fp_line
			(start 0.7874 0.4064)
			(end -0.7874 0.4064)
			(stroke
				(width 0.1524)
				(type default)
			)
			(layer "F.SilkS")
		)
		(fp_line
			(start -0.7874 0.4064)
			(end -0.7874 -0.4064)
			(stroke
				(width 0.1524)
				(type default)
			)
			(layer "F.SilkS")
		)
		(fp_line
			(start -0.12065 -0.305054)
			(end -0.12065 -0.2794)
			(stroke
				(width 0.1)
				(type default)
			)
			(layer "F.Fab")
		)
		(fp_line
			(start -0.67945 -0.305054)
			(end -0.12065 -0.305054)
			(stroke
				(width 0.1)
				(type default)
			)
			(layer "F.Fab")
		)
		(fp_line
			(start 0.67945 -0.3048)
			(end 0.67945 0.3048)
			(stroke
				(width 0.1)
				(type default)
			)
			(layer "F.Fab")
		)
		(fp_line
			(start 0.12065 -0.3048)
			(end 0.67945 -0.3048)
			(stroke
				(width 0.1)
				(type default)
			)
			(layer "F.Fab")
		)
		(fp_line
			(start 0.12065 -0.2794)
			(end 0.12065 -0.3048)
			(stroke
				(width 0.1)
				(type default)
			)
			(layer "F.Fab")
		)
		(fp_line
			(start -0.12065 -0.2794)
			(end 0.12065 -0.2794)
			(stroke
				(width 0.1)
				(type default)
			)
			(layer "F.Fab")
		)
		(fp_line
			(start 0.120396 0.2794)
			(end -0.12065 0.2794)
			(stroke
				(width 0.1)
				(type default)
			)
			(layer "F.Fab")
		)
		(fp_line
			(start -0.12065 0.2794)
			(end -0.12065 0.3048)
			(stroke
				(width 0.1)
				(type default)
			)
			(layer "F.Fab")
		)
		(fp_line
			(start 0.67945 0.3048)
			(end 0.120396 0.3048)
			(stroke
				(width 0.1)
				(type default)
			)
			(layer "F.Fab")
		)
		(fp_line
			(start 0.120396 0.3048)
			(end 0.120396 0.2794)
			(stroke
				(width 0.1)
				(type default)
			)
			(layer "F.Fab")
		)
		(fp_line
			(start -0.12065 0.3048)
			(end -0.67945 0.3048)
			(stroke
				(width 0.1)
				(type default)
			)
			(layer "F.Fab")
		)
		(fp_line
			(start -0.67945 0.3048)
			(end -0.67945 -0.305054)
			(stroke
				(width 0.1)
				(type default)
			)
			(layer "F.Fab")
		)
		(pad "1" smd circle
			(at -0.40005 0 90)
			(size 0 0)
			(layers "F.Cu" "F.Mask" "F.Paste")
			(net "CPU0_XTRIG_L4")
		)
		(pad "2" smd circle
			(at 0.40005 0 90)
			(size 0 0)
			(layers "F.Cu" "F.Mask" "F.Paste")
			(net "FM_CPU0_XTRIG_L4")
		)
	)
	(footprint ""
		(layer "F.Cu")
		(at 439.029602 -422.52011)
		(property "Reference" "PR6803"
			(at 0 0 0)
			(layer "F.SilkS")
			(hide yes)
			(effects
				(font
					(size 1.27 1.27)
				)
			)
		)
		(property "Value" ""
			(at 0 0 0)
			(layer "F.Fab")
			(effects
				(font
					(size 1.27 1.27)
				)
			)
		)
		(duplicate_pad_numbers_are_jumpers no)
		(fp_line
			(start -0.7874 -0.4064)
			(end 0.7874 -0.4064)
			(stroke
				(width 0.1524)
				(type default)
			)
			(layer "F.SilkS")
		)
		(fp_line
			(start -0.7874 0.4064)
			(end -0.7874 -0.4064)
			(stroke
				(width 0.1524)
				(type default)
			)
			(layer "F.SilkS")
		)
		(fp_line
			(start 0.7874 -0.4064)
			(end 0.7874 0.4064)
			(stroke
				(width 0.1524)
				(type default)
			)
			(layer "F.SilkS")
		)
		(fp_line
			(start 0.7874 0.4064)
			(end -0.7874 0.4064)
			(stroke
				(width 0.1524)
				(type default)
			)
			(layer "F.SilkS")
		)
		(fp_line
			(start -0.67945 -0.305054)
			(end -0.12065 -0.305054)
			(stroke
				(width 0.1)
				(type default)
			)
			(layer "F.Fab")
		)
		(fp_line
			(start -0.67945 0.3048)
			(end -0.67945 -0.305054)
			(stroke
				(width 0.1)
				(type default)
			)
			(layer "F.Fab")
		)
		(fp_line
			(start -0.12065 -0.305054)
			(end -0.12065 -0.2794)
			(stroke
				(width 0.1)
				(type default)
			)
			(layer "F.Fab")
		)
		(fp_line
			(start -0.12065 -0.2794)
			(end 0.12065 -0.2794)
			(stroke
				(width 0.1)
				(type default)
			)
			(layer "F.Fab")
		)
		(fp_line
			(start -0.12065 0.2794)
			(end -0.12065 0.3048)
			(stroke
				(width 0.1)
				(type default)
			)
			(layer "F.Fab")
		)
		(fp_line
			(start -0.12065 0.3048)
			(end -0.67945 0.3048)
			(stroke
				(width 0.1)
				(type default)
			)
			(layer "F.Fab")
		)
		(fp_line
			(start 0.120396 0.2794)
			(end -0.12065 0.2794)
			(stroke
				(width 0.1)
				(type default)
			)
			(layer "F.Fab")
		)
		(fp_line
			(start 0.120396 0.3048)
			(end 0.120396 0.2794)
			(stroke
				(width 0.1)
				(type default)
			)
			(layer "F.Fab")
		)
		(fp_line
			(start 0.12065 -0.3048)
			(end 0.67945 -0.3048)
			(stroke
				(width 0.1)
				(type default)
			)
			(layer "F.Fab")
		)
		(fp_line
			(start 0.12065 -0.2794)
			(end 0.12065 -0.3048)
			(stroke
				(width 0.1)
				(type default)
			)
			(layer "F.Fab")
		)
		(fp_line
			(start 0.67945 -0.3048)
			(end 0.67945 0.3048)
			(stroke
				(width 0.1)
				(type default)
			)
			(layer "F.Fab")
		)
		(fp_line
			(start 0.67945 0.3048)
			(end 0.120396 0.3048)
			(stroke
				(width 0.1)
				(type default)
			)
			(layer "F.Fab")
		)
		(pad "1" smd circle
			(at -0.40005 0)
			(size 0 0)
			(layers "F.Cu" "F.Mask" "F.Paste")
			(net "P3V3_AUX")
		)
		(pad "2" smd circle
			(at 0.40005 0)
			(size 0 0)
			(layers "F.Cu" "F.Mask" "F.Paste")
			(net "P0V9_RETIMER_CPU0_SVID_SDA")
		)
	)
	(footprint ""
		(layer "F.Cu")
		(at 18.650458 -418.690298 -90)
		(property "Reference" "R6176"
			(at 0 0 270)
			(layer "F.SilkS")
			(hide yes)
			(effects
				(font
					(size 1.27 1.27)
				)
			)
		)
		(property "Value" ""
			(at 0 0 270)
			(layer "F.Fab")
			(effects
				(font
					(size 1.27 1.27)
				)
			)
		)
		(duplicate_pad_numbers_are_jumpers no)
		(fp_line
			(start -0.7874 0.4064)
			(end -0.7874 -0.4064)
			(stroke
				(width 0.1524)
				(type default)
			)
			(layer "F.SilkS")
		)
		(fp_line
			(start 0.7874 0.4064)
			(end -0.7874 0.4064)
			(stroke
				(width 0.1524)
				(type default)
			)
			(layer "F.SilkS")
		)
		(fp_line
			(start -0.7874 -0.4064)
			(end 0.7874 -0.4064)
			(stroke
				(width 0.1524)
				(type default)
			)
			(layer "F.SilkS")
		)
		(fp_line
			(start 0.7874 -0.4064)
			(end 0.7874 0.4064)
			(stroke
				(width 0.1524)
				(type default)
			)
			(layer "F.SilkS")
		)
		(fp_line
			(start -0.67945 0.3048)
			(end -0.67945 -0.305054)
			(stroke
				(width 0.1)
				(type default)
			)
			(layer "F.Fab")
		)
		(fp_line
			(start -0.12065 0.3048)
			(end -0.67945 0.3048)
			(stroke
				(width 0.1)
				(type default)
			)
			(layer "F.Fab")
		)
		(fp_line
			(start 0.120396 0.3048)
			(end 0.120396 0.2794)
			(stroke
				(width 0.1)
				(type default)
			)
			(layer "F.Fab")
		)
		(fp_line
			(start 0.67945 0.3048)
			(end 0.120396 0.3048)
			(stroke
				(width 0.1)
				(type default)
			)
			(layer "F.Fab")
		)
		(fp_line
			(start -0.12065 0.2794)
			(end -0.12065 0.3048)
			(stroke
				(width 0.1)
				(type default)
			)
			(layer "F.Fab")
		)
		(fp_line
			(start 0.120396 0.2794)
			(end -0.12065 0.2794)
			(stroke
				(width 0.1)
				(type default)
			)
			(layer "F.Fab")
		)
		(fp_line
			(start -0.12065 -0.2794)
			(end 0.12065 -0.2794)
			(stroke
				(width 0.1)
				(type default)
			)
			(layer "F.Fab")
		)
		(fp_line
			(start 0.12065 -0.2794)
			(end 0.12065 -0.3048)
			(stroke
				(width 0.1)
				(type default)
			)
			(layer "F.Fab")
		)
		(fp_line
			(start 0.12065 -0.3048)
			(end 0.67945 -0.3048)
			(stroke
				(width 0.1)
				(type default)
			)
			(layer "F.Fab")
		)
		(fp_line
			(start 0.67945 -0.3048)
			(end 0.67945 0.3048)
			(stroke
				(width 0.1)
				(type default)
			)
			(layer "F.Fab")
		)
		(fp_line
			(start -0.67945 -0.305054)
			(end -0.12065 -0.305054)
			(stroke
				(width 0.1)
				(type default)
			)
			(layer "F.Fab")
		)
		(fp_line
			(start -0.12065 -0.305054)
			(end -0.12065 -0.2794)
			(stroke
				(width 0.1)
				(type default)
			)
			(layer "F.Fab")
		)
		(pad "1" smd circle
			(at -0.40005 0 270)
			(size 0 0)
			(layers "F.Cu" "F.Mask" "F.Paste")
			(net "FM_P2E_BUF2_RXDET")
		)
		(pad "2" smd circle
			(at 0.40005 0 270)
			(size 0 0)
			(layers "F.Cu" "F.Mask" "F.Paste")
			(net "GND")
		)
	)
	(footprint ""
		(layer "F.Cu")
		(at 399.352262 -416.899344 -90)
		(property "Reference" "C6583"
			(at 0 0 270)
			(layer "F.SilkS")
			(hide yes)
			(effects
				(font
					(size 1.27 1.27)
				)
			)
		)
		(property "Value" ""
			(at 0 0 270)
			(layer "F.Fab")
			(effects
				(font
					(size 1.27 1.27)
				)
			)
		)
		(duplicate_pad_numbers_are_jumpers no)
		(fp_line
			(start -0.299974 0.150114)
			(end -0.299974 -0.150114)
			(stroke
				(width 0.1)
				(type default)
			)
			(layer "F.Fab")
		)
		(fp_line
			(start 0.299974 0.150114)
			(end -0.299974 0.150114)
			(stroke
				(width 0.1)
				(type default)
			)
			(layer "F.Fab")
		)
		(fp_line
			(start -0.299974 -0.150114)
			(end 0.299974 -0.150114)
			(stroke
				(width 0.1)
				(type default)
			)
			(layer "F.Fab")
		)
		(fp_line
			(start 0.299974 -0.150114)
			(end 0.299974 0.150114)
			(stroke
				(width 0.1)
				(type default)
			)
			(layer "F.Fab")
		)
		(pad "1" smd rect
			(at -0.2667 0 270)
			(size 0.3048 0.381)
			(layers "F.Cu" "F.Mask" "F.Paste")
			(net "P5E_CPU0_P2_TX_BUF_C_DP<9>")
		)
		(pad "2" smd rect
			(at 0.2667 0 270)
			(size 0.3048 0.381)
			(layers "F.Cu" "F.Mask" "F.Paste")
			(net "P5E_CPU0_P2_TX_BUF_DP<9>")
		)
	)
)
